(kicad_pcb
	(version 20260206)
	(generator "pcbnew")
	(generator_version "10.0")
	(general
		(thickness 1.6)
		(legacy_teardrops no)
	)
	(paper "A4")
	(title_block
		(title "Bryce Canyon_F.DPB_16315-1-OCP.brd")
		(comment 1 "Bryce Canyon / footprints 368-373 of 2223")
	)
	(layers
		(0 "F.Cu" signal "TOP")
		(4 "In1.Cu" signal "L2GND")
		(6 "In2.Cu" signal "L3")
		(8 "In3.Cu" signal "L4GND")
		(10 "In4.Cu" signal "L5")
		(12 "In5.Cu" signal "L6VCC")
		(14 "In6.Cu" signal "L7VCC")
		(16 "In7.Cu" signal "L8")
		(18 "In8.Cu" signal "L9GND")
		(20 "In9.Cu" signal "L10")
		(22 "In10.Cu" signal "L11GND")
		(2 "B.Cu" signal "BOTTOM")
		(9 "F.Adhes" user "F.Adhesive")
		(11 "B.Adhes" user "B.Adhesive")
		(13 "F.Paste" user "Package Geometry/Pastemask Top")
		(15 "B.Paste" user "Package Geometry/Pastemask Bottom")
		(5 "F.SilkS" user "Ref Des/Silkscreen Top")
		(7 "B.SilkS" user "Ref Des/Silkscreen Bottom")
		(1 "F.Mask" user "Board Geometry/Soldermask Top")
		(3 "B.Mask" user "Board Geometry/Soldermask Bottom")
		(17 "Dwgs.User" user "User.Drawings")
		(19 "Cmts.User" user "User.Comments")
		(21 "Eco1.User" user "User.Eco1")
		(23 "Eco2.User" user "User.Eco2")
		(25 "Edge.Cuts" user "Board Geometry/Outline")
		(27 "Margin" user)
		(31 "F.CrtYd" user "Package Geometry/Place Bound Top")
		(29 "B.CrtYd" user "Package Geometry/Place Bound Bottom")
		(35 "F.Fab" user "Ref Des/Assembly Top")
		(33 "B.Fab" user "Ref Des/Assembly Bottom")
	)
	(footprint ""
		(layer "F.Cu")
		(at 144.977866 -137.879074)
		(property "Reference" "U23"
			(at 0 0 0)
			(layer "F.SilkS")
			(hide yes)
			(effects
				(font
					(size 1.27 1.27)
				)
			)
		)
		(property "Value" "ADM1278-2ACPZ-RL-1-GP"
			(at -4.7625 -7.4422 0)
			(unlocked yes)
			(layer "F.Fab")
			(hide yes)
			(effects
				(font
					(size 1.016 1.016)
					(thickness 0.1524)
				)
			)
		)
		(property "Device Type" "QFN32-G3D45-UH32"
			(at -4.7625 -8.9662 0)
			(unlocked yes)
			(layer "F.Fab")
			(hide yes)
			(effects
				(font
					(size 1.016 1.016)
					(thickness 0.1524)
				)
			)
		)
		(duplicate_pad_numbers_are_jumpers no)
		(fp_line
			(start -4.0513 -1.24968)
			(end -3.2893 -1.24968)
			(stroke
				(width 0.1524)
				(type default)
			)
			(layer "F.SilkS")
		)
		(fp_line
			(start -3.7973 1.24968)
			(end -3.2893 1.24968)
			(stroke
				(width 0.1524)
				(type default)
			)
			(layer "F.SilkS")
		)
		(fp_line
			(start -3.5179 -3.5179)
			(end -2.2479 -3.5179)
			(stroke
				(width 0.1524)
				(type default)
			)
			(layer "F.SilkS")
		)
		(fp_line
			(start -3.5179 -2.2479)
			(end -3.5179 -3.5179)
			(stroke
				(width 0.1524)
				(type default)
			)
			(layer "F.SilkS")
		)
		(fp_line
			(start -3.5179 2.2479)
			(end -3.5179 3.5179)
			(stroke
				(width 0.1524)
				(type default)
			)
			(layer "F.SilkS")
		)
		(fp_line
			(start -3.5179 3.5179)
			(end -2.2479 3.5179)
			(stroke
				(width 0.1524)
				(type default)
			)
			(layer "F.SilkS")
		)
		(fp_line
			(start -0.250698 -3.7973)
			(end -0.250698 -3.2893)
			(stroke
				(width 0.1524)
				(type default)
			)
			(layer "F.SilkS")
		)
		(fp_line
			(start -0.250698 4.0513)
			(end -0.250698 3.2893)
			(stroke
				(width 0.1524)
				(type default)
			)
			(layer "F.SilkS")
		)
		(fp_line
			(start 3.5179 2.2479)
			(end 3.5179 3.5179)
			(stroke
				(width 0.1524)
				(type default)
			)
			(layer "F.SilkS")
		)
		(fp_line
			(start 3.5179 3.5179)
			(end 2.2479 3.5179)
			(stroke
				(width 0.1524)
				(type default)
			)
			(layer "F.SilkS")
		)
		(fp_line
			(start 3.7973 1.749552)
			(end 3.2893 1.749552)
			(stroke
				(width 0.1524)
				(type default)
			)
			(layer "F.SilkS")
		)
		(fp_line
			(start 4.0513 -0.749808)
			(end 3.2893 -0.749808)
			(stroke
				(width 0.1524)
				(type default)
			)
			(layer "F.SilkS")
		)
		(fp_poly
			(pts
				(xy 2.2479 -3.5179) (xy 3.5179 -2.2479) (xy 3.5179 -3.5179)
			)
			(stroke
				(width 0)
				(type default)
			)
			(fill yes)
			(layer "F.SilkS")
		)
		(fp_rect
			(start -2.5019 2.5019)
			(end 2.5019 -2.5019)
			(stroke
				(width 0)
				(type default)
			)
			(fill no)
			(layer "F.CrtYd")
		)
		(fp_poly
			(pts
				(xy -3.5179 3.5179) (xy -3.5179 -3.5179) (xy 3.5179 -3.5179) (xy 3.5179 3.5179) (xy -2.49682 3.5179)
				(xy -2.49682 2.5019) (xy 2.5019 2.5019) (xy 2.5019 -2.5019) (xy -2.5019 -2.5019) (xy -2.5019 3.5179)
			)
			(stroke
				(width 0)
				(type default)
			)
			(fill no)
			(layer "F.CrtYd")
		)
		(fp_rect
			(start -3.5179 3.5179)
			(end 3.5179 -3.5179)
			(stroke
				(width 0)
				(type default)
			)
			(fill no)
			(layer "F.Fab")
		)
		(pad "1" smd rect
			(at 1.75006 -2.5527)
			(size 0.3048 0.9144)
			(layers "F.Cu" "F.Mask" "F.Paste")
			(net "MB0_PSET_R")
		)
		(pad "2" smd rect
			(at 1.249934 -2.4765)
			(size 0.3048 1.0668)
			(layers "F.Cu" "F.Mask" "F.Paste")
			(net "MB0_VCAP_R")
		)
		(pad "3" smd rect
			(at 0.750062 -2.4765)
			(size 0.3048 1.0668)
			(layers "F.Cu" "F.Mask" "F.Paste")
			(net "MB0_ISET_R")
		)
		(pad "4" smd rect
			(at 0.249936 -2.4765)
			(size 0.3048 1.0668)
			(layers "F.Cu" "F.Mask" "F.Paste")
			(net "MB0_ISTART_R")
		)
		(pad "5" smd rect
			(at -0.249936 -2.4765)
			(size 0.3048 1.0668)
			(layers "F.Cu" "F.Mask" "F.Paste")
			(net "MB0_TIME_R")
		)
		(pad "6" smd rect
			(at -0.750062 -2.4765)
			(size 0.3048 1.0668)
			(layers "F.Cu" "F.Mask" "F.Paste")
			(net "Net_1360")
		)
		(pad "7" smd rect
			(at -1.249934 -2.4765)
			(size 0.3048 1.0668)
			(layers "F.Cu" "F.Mask" "F.Paste")
			(net "MB0_CM_ADR1_R")
		)
		(pad "8" smd rect
			(at -1.75006 -2.5527)
			(size 0.3048 0.9144)
			(layers "F.Cu" "F.Mask" "F.Paste")
			(net "MB0_CM_ADR2_R")
		)
		(pad "9" smd rect
			(at -2.5527 -1.75006)
			(size 0.9144 0.3048)
			(layers "F.Cu" "F.Mask" "F.Paste")
			(net "MB0_SPISS_PD")
		)
		(pad "10" smd rect
			(at -2.4765 -1.249934)
			(size 1.0668 0.3048)
			(layers "F.Cu" "F.Mask" "F.Paste")
			(net "Net_1364")
		)
		(pad "11" smd rect
			(at -2.4765 -0.750062)
			(size 1.0668 0.3048)
			(layers "F.Cu" "F.Mask" "F.Paste")
			(net "Net_1363")
		)
		(pad "12" smd rect
			(at -2.4765 -0.249936)
			(size 1.0668 0.3048)
			(layers "F.Cu" "F.Mask" "F.Paste")
			(net "MB0_HS_ENABLE")
		)
		(pad "13" smd rect
			(at -2.4765 0.249936)
			(size 1.0668 0.3048)
			(layers "F.Cu" "F.Mask" "F.Paste")
			(net "Net_1362")
		)
		(pad "14" smd rect
			(at -2.4765 0.750062)
			(size 1.0668 0.3048)
			(layers "F.Cu" "F.Mask" "F.Paste")
			(net "Net_1361")
		)
		(pad "15" smd rect
			(at -2.4765 1.249934)
			(size 1.0668 0.3048)
			(layers "F.Cu" "F.Mask" "F.Paste")
			(net "MB0_SDA_R")
		)
		(pad "16" smd rect
			(at -2.5527 1.75006)
			(size 0.9144 0.3048)
			(layers "F.Cu" "F.Mask" "F.Paste")
			(net "MB0_SCL_R")
		)
		(pad "17" smd rect
			(at -1.75006 2.5527)
			(size 0.3048 0.9144)
			(layers "F.Cu" "F.Mask" "F.Paste")
			(net "MB0_RETRY_R")
		)
		(pad "18" smd rect
			(at -1.249934 2.4765)
			(size 0.3048 1.0668)
			(layers "F.Cu" "F.Mask" "F.Paste")
			(net "COMP_A_PGOOD")
		)
		(pad "19" smd rect
			(at -0.750062 2.4765)
			(size 0.3048 1.0668)
			(layers "F.Cu" "F.Mask" "F.Paste")
			(net "Net_1365")
		)
		(pad "20" smd rect
			(at -0.249936 2.4765)
			(size 0.3048 1.0668)
			(layers "F.Cu" "F.Mask" "F.Paste")
			(net "MB0_CM_VOUT_R")
		)
		(pad "21" smd rect
			(at 0.249936 2.4765)
			(size 0.3048 1.0668)
			(layers "F.Cu" "F.Mask" "F.Paste")
			(net "MB0_P12V_PWGIN_R")
		)
		(pad "22" smd rect
			(at 0.750062 2.4765)
			(size 0.3048 1.0668)
			(layers "F.Cu" "F.Mask" "F.Paste")
			(net "AGND_CURRENT_MONOA")
		)
		(pad "23" smd rect
			(at 1.249934 2.4765)
			(size 0.3048 1.0668)
			(layers "F.Cu" "F.Mask" "F.Paste")
			(net "GND")
		)
		(pad "24" smd rect
			(at 1.75006 2.5527)
			(size 0.3048 0.9144)
			(layers "F.Cu" "F.Mask" "F.Paste")
			(net "MB0_CM_GATE")
		)
		(pad "25" smd rect
			(at 2.5527 1.75006)
			(size 0.9144 0.3048)
			(layers "F.Cu" "F.Mask" "F.Paste")
			(net "MB0_TEMP")
		)
		(pad "26" smd rect
			(at 2.4765 1.249934)
			(size 1.0668 0.3048)
			(layers "F.Cu" "F.Mask" "F.Paste")
			(net "MB0_CM_SENSE_N")
		)
		(pad "27" smd rect
			(at 2.4765 0.750062)
			(size 1.0668 0.3048)
			(layers "F.Cu" "F.Mask" "F.Paste")
			(net "MB0_HS_SENSE_N")
		)
		(pad "28" smd rect
			(at 2.4765 0.249936)
			(size 1.0668 0.3048)
			(layers "F.Cu" "F.Mask" "F.Paste")
			(net "MB0_HS_SENSE_P")
		)
		(pad "29" smd rect
			(at 2.4765 -0.249936)
			(size 1.0668 0.3048)
			(layers "F.Cu" "F.Mask" "F.Paste")
			(net "MB0_CM_SENSE_P")
		)
		(pad "30" smd rect
			(at 2.4765 -0.750062)
			(size 1.0668 0.3048)
			(layers "F.Cu" "F.Mask" "F.Paste")
			(net "MB0_P12V_HS")
		)
		(pad "31" smd rect
			(at 2.4765 -1.249934)
			(size 1.0668 0.3048)
			(layers "F.Cu" "F.Mask" "F.Paste")
			(net "MB0_CM_UV_R")
		)
		(pad "32" smd rect
			(at 2.5527 -1.75006)
			(size 0.9144 0.3048)
			(layers "F.Cu" "F.Mask" "F.Paste")
			(net "MB0_CM_OV_R")
		)
		(pad "33" smd rect
			(at 0 0)
			(size 3.4544 3.4544)
			(layers "F.Cu" "F.Mask" "F.Paste")
			(net "AGND_CURRENT_MONOA")
		)
	)
	(footprint ""
		(layer "F.Cu")
		(at 424.469052 -74.335894 180)
		(property "Reference" "C476"
			(at 0 0 180)
			(layer "F.SilkS")
			(hide yes)
			(effects
				(font
					(size 1.27 1.27)
				)
			)
		)
		(property "Value" "SC1U25V3KX-GP"
			(at 0 -2.8194 180)
			(unlocked yes)
			(layer "F.Fab")
			(hide yes)
			(effects
				(font
					(size 1.016 1.016)
					(thickness 0.1524)
				)
			)
		)
		(property "Device Type" "C603H36"
			(at 0 -4.3434 180)
			(unlocked yes)
			(layer "F.Fab")
			(hide yes)
			(effects
				(font
					(size 1.016 1.016)
					(thickness 0.1524)
				)
			)
		)
		(duplicate_pad_numbers_are_jumpers no)
		(fp_line
			(start 0.508 0)
			(end -0.508 0)
			(stroke
				(width 0.2032)
				(type default)
			)
			(layer "F.SilkS")
		)
		(fp_rect
			(start -0.5842 1.3335)
			(end 0.5842 -1.3335)
			(stroke
				(width 0)
				(type default)
			)
			(fill no)
			(layer "F.CrtYd")
		)
		(fp_rect
			(start -0.5842 1.3335)
			(end 0.5842 -1.3335)
			(stroke
				(width 0)
				(type default)
			)
			(fill no)
			(layer "F.Fab")
		)
		(pad "1" smd custom
			(at 0 -0.762 180)
			(size 0.2159 0.2159)
			(layers "F.Cu" "F.Mask" "F.Paste")
			(net "P12V_HDD33")
			(options
				(clearance outline)
				(anchor circle)
			)
			(primitives
				(gr_poly
					(pts
						(arc
							(start -0.3302 -0.4318)
							(mid -0.402042 -0.402042)
							(end -0.4318 -0.3302)
						)
						(arc
							(start -0.4318 0.3302)
							(mid -0.402042 0.402042)
							(end -0.3302 0.4318)
						)
						(arc
							(start 0.3302 0.4318)
							(mid 0.402042 0.402042)
							(end 0.4318 0.3302)
						)
						(arc
							(start 0.4318 -0.3302)
							(mid 0.402042 -0.402042)
							(end 0.3302 -0.4318)
						)
					)
					(width 0)
					(fill yes)
				)
			)
		)
		(pad "2" smd custom
			(at 0 0.762 180)
			(size 0.2159 0.2159)
			(layers "F.Cu" "F.Mask" "F.Paste")
			(net "GND")
			(options
				(clearance outline)
				(anchor circle)
			)
			(primitives
				(gr_poly
					(pts
						(arc
							(start -0.3302 -0.4318)
							(mid -0.402042 -0.402042)
							(end -0.4318 -0.3302)
						)
						(arc
							(start -0.4318 0.3302)
							(mid -0.402042 0.402042)
							(end -0.3302 0.4318)
						)
						(arc
							(start 0.3302 0.4318)
							(mid 0.402042 0.402042)
							(end 0.4318 0.3302)
						)
						(arc
							(start 0.4318 -0.3302)
							(mid 0.402042 -0.402042)
							(end 0.3302 -0.4318)
						)
					)
					(width 0)
					(fill yes)
				)
			)
		)
	)
	(footprint ""
		(layer "F.Cu")
		(at 50.456846 -64.683894 90)
		(property "Reference" "R706"
			(at 0 0 90)
			(layer "F.SilkS")
			(hide yes)
			(effects
				(font
					(size 1.27 1.27)
				)
			)
		)
		(property "Value" "2R6F-GP"
			(at -0.0508 -4.8514 90)
			(unlocked yes)
			(layer "F.Fab")
			(hide yes)
			(effects
				(font
					(size 1.016 1.016)
					(thickness 0.1524)
				)
			)
		)
		(property "Device Type" "R1206H26"
			(at 0 -6.3754 90)
			(unlocked yes)
			(layer "F.Fab")
			(hide yes)
			(effects
				(font
					(size 1.016 1.016)
					(thickness 0.1524)
				)
			)
		)
		(duplicate_pad_numbers_are_jumpers no)
		(fp_line
			(start 1.016 -2.2352)
			(end 1.016 2.2352)
			(stroke
				(width 0.1524)
				(type default)
			)
			(layer "F.SilkS")
		)
		(fp_line
			(start -1.016 -2.2352)
			(end 1.016 -2.2352)
			(stroke
				(width 0.1524)
				(type default)
			)
			(layer "F.SilkS")
		)
		(fp_line
			(start 1.016 2.2352)
			(end -1.016 2.2352)
			(stroke
				(width 0.1524)
				(type default)
			)
			(layer "F.SilkS")
		)
		(fp_line
			(start -1.016 2.2352)
			(end -1.016 -2.2352)
			(stroke
				(width 0.1524)
				(type default)
			)
			(layer "F.SilkS")
		)
		(fp_rect
			(start -1.0922 2.3114)
			(end 1.0922 -2.3114)
			(stroke
				(width 0)
				(type default)
			)
			(fill no)
			(layer "F.CrtYd")
		)
		(fp_poly
			(pts
				(xy -1.0922 -2.3114) (xy 1.0922 -2.3114) (xy 1.0922 2.3114) (xy -1.0922 2.3114)
			)
			(stroke
				(width 0)
				(type default)
			)
			(fill no)
			(layer "F.Fab")
		)
		(pad "1" smd rect
			(at 0 -1.397 90)
			(size 1.651 1.27)
			(layers "F.Cu" "F.Mask" "F.Paste")
			(net "P12V_HDD25")
		)
		(pad "2" smd rect
			(at 0 1.397 90)
			(size 1.651 1.27)
			(layers "F.Cu" "F.Mask" "F.Paste")
			(net "12V_PRE_25")
		)
	)
	(footprint ""
		(layer "F.Cu")
		(at 318.389 -65.064894 -90)
		(property "Reference" "R824"
			(at 0 0 270)
			(layer "F.SilkS")
			(hide yes)
			(effects
				(font
					(size 1.27 1.27)
				)
			)
		)
		(property "Value" "220R3F-1-GP"
			(at -0.0254 -2.5146 270)
			(unlocked yes)
			(layer "F.Fab")
			(hide yes)
			(effects
				(font
					(size 1.016 1.016)
					(thickness 0.1524)
				)
			)
		)
		(property "Device Type" "R603H22"
			(at -0.0254 -4.0386 270)
			(unlocked yes)
			(layer "F.Fab")
			(hide yes)
			(effects
				(font
					(size 1.016 1.016)
					(thickness 0.1524)
				)
			)
		)
		(duplicate_pad_numbers_are_jumpers no)
		(fp_line
			(start -0.4826 0)
			(end -0.2032 0)
			(stroke
				(width 0.2032)
				(type default)
			)
			(layer "F.SilkS")
		)
		(fp_line
			(start 0.2032 0)
			(end 0.4826 0)
			(stroke
				(width 0.2032)
				(type default)
			)
			(layer "F.SilkS")
		)
		(fp_rect
			(start -0.5842 1.3335)
			(end 0.5842 -1.3335)
			(stroke
				(width 0)
				(type default)
			)
			(fill no)
			(layer "F.CrtYd")
		)
		(fp_rect
			(start -0.5842 1.3335)
			(end 0.5842 -1.3335)
			(stroke
				(width 0)
				(type default)
			)
			(fill no)
			(layer "F.Fab")
		)
		(pad "1" smd custom
			(at 0 -0.762 270)
			(size 0.2159 0.2159)
			(layers "F.Cu" "F.Mask" "F.Paste")
			(net "HDD_PRSNT_30")
			(options
				(clearance outline)
				(anchor circle)
			)
			(primitives
				(gr_poly
					(pts
						(arc
							(start -0.3302 -0.4318)
							(mid -0.402042 -0.402042)
							(end -0.4318 -0.3302)
						)
						(arc
							(start -0.4318 0.3302)
							(mid -0.402042 0.402042)
							(end -0.3302 0.4318)
						)
						(arc
							(start 0.3302 0.4318)
							(mid 0.402042 0.402042)
							(end 0.4318 0.3302)
						)
						(arc
							(start 0.4318 -0.3302)
							(mid 0.402042 -0.402042)
							(end 0.3302 -0.4318)
						)
					)
					(width 0)
					(fill yes)
				)
			)
		)
		(pad "2" smd custom
			(at 0 0.762 270)
			(size 0.2159 0.2159)
			(layers "F.Cu" "F.Mask" "F.Paste")
			(net "DRIVE_A_30_INS")
			(options
				(clearance outline)
				(anchor circle)
			)
			(primitives
				(gr_poly
					(pts
						(arc
							(start -0.3302 -0.4318)
							(mid -0.402042 -0.402042)
							(end -0.4318 -0.3302)
						)
						(arc
							(start -0.4318 0.3302)
							(mid -0.402042 0.402042)
							(end -0.3302 0.4318)
						)
						(arc
							(start 0.3302 0.4318)
							(mid 0.402042 0.402042)
							(end 0.4318 0.3302)
						)
						(arc
							(start 0.4318 -0.3302)
							(mid 0.402042 -0.402042)
							(end 0.3302 -0.4318)
						)
					)
					(width 0)
					(fill yes)
				)
			)
		)
	)
	(footprint ""
		(layer "F.Cu")
		(at 457.6699 -303.954942 180)
		(property "Reference" "C174"
			(at 0 0 180)
			(layer "F.SilkS")
			(hide yes)
			(effects
				(font
					(size 1.27 1.27)
				)
			)
		)
		(property "Value" "SC4D7U25V5KX-1-GP"
			(at -0.0762 -6.1214 180)
			(unlocked yes)
			(layer "F.Fab")
			(hide yes)
			(effects
				(font
					(size 1.016 1.016)
					(thickness 0.1524)
				)
			)
		)
		(property "Device Type" "C805H58"
			(at -0.0762 -8.1534 180)
			(unlocked yes)
			(layer "F.Fab")
			(hide yes)
			(effects
				(font
					(size 1.016 1.016)
					(thickness 0.1524)
				)
			)
		)
		(duplicate_pad_numbers_are_jumpers no)
		(fp_line
			(start 0.635 0)
			(end -0.635 0)
			(stroke
				(width 0.508)
				(type default)
			)
			(layer "F.SilkS")
		)
		(fp_rect
			(start -0.9652 1.778)
			(end 0.9652 -1.778)
			(stroke
				(width 0)
				(type default)
			)
			(fill no)
			(layer "F.CrtYd")
		)
		(fp_poly
			(pts
				(xy -0.9652 -1.778) (xy 0.9652 -1.778) (xy 0.9652 1.778) (xy -0.9652 1.778)
			)
			(stroke
				(width 0)
				(type default)
			)
			(fill no)
			(layer "F.Fab")
		)
		(pad "1" smd rect
			(at 0 -0.9652 180)
			(size 1.397 1.143)
			(layers "F.Cu" "F.Mask" "F.Paste")
			(net "P12V_HDD10")
		)
		(pad "2" smd rect
			(at 0 0.9652 180)
			(size 1.397 1.143)
			(layers "F.Cu" "F.Mask" "F.Paste")
			(net "GND")
		)
	)
	(footprint ""
		(layer "F.Cu")
		(at 255.389634 -6.741922 90)
		(property "Reference" "TP214"
			(at 0 0 90)
			(layer "F.SilkS")
			(hide yes)
			(effects
				(font
					(size 1.27 1.27)
				)
			)
		)
		(property "Value" "TPAD32-GP"
			(at -0.0508 -1.6764 90)
			(unlocked yes)
			(layer "F.Fab")
			(hide yes)
			(effects
				(font
					(size 1.016 1.016)
					(thickness 0.1524)
				)
			)
		)
		(property "Device Type" "TPAD32"
			(at -0.0508 -3.2004 90)
			(unlocked yes)
			(layer "F.Fab")
			(hide yes)
			(effects
				(font
					(size 1.016 1.016)
					(thickness 0.1524)
				)
			)
		)
		(duplicate_pad_numbers_are_jumpers no)
		(fp_poly
			(pts
				(arc
					(start 0 0.4064)
					(mid 0 -0.4064)
					(end 0 0.4064)
				)
			)
			(stroke
				(width 0)
				(type default)
			)
			(fill no)
			(layer "F.CrtYd")
		)
		(fp_poly
			(pts
				(arc
					(start 0 0.7112)
					(mid 0 -0.7112)
					(end 0 0.7112)
				)
			)
			(stroke
				(width 0)
				(type default)
			)
			(fill no)
			(layer "F.Fab")
		)
		(pad "1" smd circle
			(at 0 0 90)
			(size 0.8128 0.8128)
			(layers "F.Cu" "F.Mask" "F.Paste")
			(net "TP_COMP_A_NCSI_TXD0")
		)
	)
)
